# S9S_MB_2U (Grand Teton) — schematic netlist excerpt (pin names and nets, part order shuffled) for the footprints in the layout excerpt that follows; sources: Cadence DE-HDL packaged netlist, KiCad conversion of 03242023_DA0F0TMBIJ0_F0T_Motherboard_J_brd_V01_OCP.brd

PL119  Q_INDUCTOR  0.68UH IND  pkg SMLF  page 299 : \1\ = SW_PVPP_HBM_CPU1_SW ; \2\ = PVPP_HBM_CPU1
C934  Q_CAP_DIFFBUS  DIFF BUS_0.22UF 6.3V 20% X6S  pkg C0201  page 173 : \1\ = P5E_CPU0_PE2_TX_C_DN<15> ; \2\ = P5E_CPU0_PE2_TX_DN<15>
C1875  Q_CAP  0.1UF 25V 10% X7R  pkg 0402  page 165 : A = P3V3_AUX ; B = GND

(kicad_pcb
	(version 20260206)
	(generator "pcbnew")
	(generator_version "10.0")
	(general
		(thickness 1.6)
		(legacy_teardrops no)
	)
	(paper "A4")
	(title_block
		(title "03242023_DA0F0TMBIJ0_F0T_Motherboard_J_brd_V01_OCP.brd")
		(comment 1 "Grand Teton / footprints 2109-2111 of 6105")
	)
	(layers
		(0 "F.Cu" signal "TOP")
		(4 "In1.Cu" signal "GND")
		(6 "In2.Cu" signal "IN1")
		(8 "In3.Cu" signal "GND1")
		(10 "In4.Cu" signal "IN2")
		(12 "In5.Cu" signal "GND2")
		(14 "In6.Cu" signal "IN3")
		(16 "In7.Cu" signal "GND3")
		(18 "In8.Cu" signal "VCC")
		(20 "In9.Cu" signal "VCC1")
		(22 "In10.Cu" signal "GND4")
		(24 "In11.Cu" signal "IN4")
		(26 "In12.Cu" signal "GND5")
		(28 "In13.Cu" signal "IN5")
		(30 "In14.Cu" signal "GND6")
		(32 "In15.Cu" signal "IN6")
		(34 "In16.Cu" signal "GND7")
		(2 "B.Cu" signal "BOTTOM")
		(9 "F.Adhes" user "F.Adhesive")
		(11 "B.Adhes" user "B.Adhesive")
		(13 "F.Paste" user "Package Geometry/Pastemask Top")
		(15 "B.Paste" user "Package Geometry/Pastemask Bottom")
		(5 "F.SilkS" user "Ref Des/Silkscreen Top")
		(7 "B.SilkS" user "Ref Des/Silkscreen Bottom")
		(1 "F.Mask" user "Board Geometry/Soldermask Top")
		(3 "B.Mask" user "Board Geometry/Soldermask Bottom")
		(17 "Dwgs.User" user "User.Drawings")
		(19 "Cmts.User" user "User.Comments")
		(21 "Eco1.User" user "User.Eco1")
		(23 "Eco2.User" user "User.Eco2")
		(25 "Edge.Cuts" user "Board Geometry/Outline")
		(27 "Margin" user)
		(31 "F.CrtYd" user "Package Geometry/Place Bound Top")
		(29 "B.CrtYd" user "Package Geometry/Place Bound Bottom")
		(35 "F.Fab" user "Ref Des/Assembly Top")
		(33 "B.Fab" user "Ref Des/Assembly Bottom")
	)
	(footprint ""
		(layer "F.Cu")
		(at 8.80872 -76.827888)
		(property "Reference" "C1875"
			(at 0 0 0)
			(layer "F.SilkS")
			(hide yes)
			(effects
				(font
					(size 1.27 1.27)
				)
			)
		)
		(property "Value" ""
			(at 0 0 0)
			(layer "F.Fab")
			(effects
				(font
					(size 1.27 1.27)
				)
			)
		)
		(duplicate_pad_numbers_are_jumpers no)
		(fp_line
			(start -0.7874 -0.4064)
			(end 0.7874 -0.4064)
			(stroke
				(width 0.1524)
				(type default)
			)
			(layer "F.SilkS")
		)
		(fp_line
			(start -0.7874 0.4064)
			(end -0.7874 -0.4064)
			(stroke
				(width 0.1524)
				(type default)
			)
			(layer "F.SilkS")
		)
		(fp_line
			(start 0.7874 -0.4064)
			(end 0.7874 0.4064)
			(stroke
				(width 0.1524)
				(type default)
			)
			(layer "F.SilkS")
		)
		(fp_line
			(start 0.7874 0.4064)
			(end -0.7874 0.4064)
			(stroke
				(width 0.1524)
				(type default)
			)
			(layer "F.SilkS")
		)
		(fp_line
			(start -0.67945 -0.305054)
			(end -0.12065 -0.305054)
			(stroke
				(width 0.1)
				(type default)
			)
			(layer "F.Fab")
		)
		(fp_line
			(start -0.67945 0.3048)
			(end -0.67945 -0.305054)
			(stroke
				(width 0.1)
				(type default)
			)
			(layer "F.Fab")
		)
		(fp_line
			(start -0.12065 -0.305054)
			(end -0.12065 -0.2794)
			(stroke
				(width 0.1)
				(type default)
			)
			(layer "F.Fab")
		)
		(fp_line
			(start -0.12065 -0.2794)
			(end 0.12065 -0.2794)
			(stroke
				(width 0.1)
				(type default)
			)
			(layer "F.Fab")
		)
		(fp_line
			(start -0.12065 0.2794)
			(end -0.12065 0.3048)
			(stroke
				(width 0.1)
				(type default)
			)
			(layer "F.Fab")
		)
		(fp_line
			(start -0.12065 0.3048)
			(end -0.67945 0.3048)
			(stroke
				(width 0.1)
				(type default)
			)
			(layer "F.Fab")
		)
		(fp_line
			(start 0.120396 0.2794)
			(end -0.12065 0.2794)
			(stroke
				(width 0.1)
				(type default)
			)
			(layer "F.Fab")
		)
		(fp_line
			(start 0.120396 0.3048)
			(end 0.120396 0.2794)
			(stroke
				(width 0.1)
				(type default)
			)
			(layer "F.Fab")
		)
		(fp_line
			(start 0.12065 -0.3048)
			(end 0.67945 -0.3048)
			(stroke
				(width 0.1)
				(type default)
			)
			(layer "F.Fab")
		)
		(fp_line
			(start 0.12065 -0.2794)
			(end 0.12065 -0.3048)
			(stroke
				(width 0.1)
				(type default)
			)
			(layer "F.Fab")
		)
		(fp_line
			(start 0.67945 -0.3048)
			(end 0.67945 0.3048)
			(stroke
				(width 0.1)
				(type default)
			)
			(layer "F.Fab")
		)
		(fp_line
			(start 0.67945 0.3048)
			(end 0.120396 0.3048)
			(stroke
				(width 0.1)
				(type default)
			)
			(layer "F.Fab")
		)
		(pad "1" smd circle
			(at -0.40005 0)
			(size 0 0)
			(layers "F.Cu" "F.Mask" "F.Paste")
			(net "P3V3_AUX")
		)
		(pad "2" smd circle
			(at 0.40005 0)
			(size 0 0)
			(layers "F.Cu" "F.Mask" "F.Paste")
			(net "GND")
		)
	)
	(footprint ""
		(layer "F.Cu")
		(at 125.711204 -366.689132 90)
		(property "Reference" "PL119"
			(at -3.896614 4.481576 0)
			(unlocked yes)
			(layer "F.SilkS")
			(effects
				(font
					(size 0.7874 0.5842)
					(thickness 0.1524)
				)
				(justify left)
			)
		)
		(property "Value" ""
			(at 0 0 90)
			(layer "F.Fab")
			(effects
				(font
					(size 1.27 1.27)
				)
			)
		)
		(duplicate_pad_numbers_are_jumpers no)
		(fp_line
			(start 3.64998 -3.350006)
			(end 3.64998 -1.8034)
			(stroke
				(width 0.1524)
				(type default)
			)
			(layer "F.SilkS")
		)
		(fp_line
			(start -3.6576 -3.350006)
			(end 3.64998 -3.350006)
			(stroke
				(width 0.1524)
				(type default)
			)
			(layer "F.SilkS")
		)
		(fp_line
			(start -3.64998 -1.8034)
			(end -3.64998 -3.350006)
			(stroke
				(width 0.1524)
				(type default)
			)
			(layer "F.SilkS")
		)
		(fp_line
			(start 3.64998 1.8034)
			(end 3.64998 3.350006)
			(stroke
				(width 0.1524)
				(type default)
			)
			(layer "F.SilkS")
		)
		(fp_line
			(start 3.64998 3.350006)
			(end -3.64998 3.350006)
			(stroke
				(width 0.1524)
				(type default)
			)
			(layer "F.SilkS")
		)
		(fp_line
			(start -3.64998 3.350006)
			(end -3.64998 1.8288)
			(stroke
				(width 0.1524)
				(type default)
			)
			(layer "F.SilkS")
		)
		(fp_line
			(start 3.64998 -3.350006)
			(end 3.64998 3.350006)
			(stroke
				(width 0.1)
				(type default)
			)
			(layer "F.Fab")
		)
		(fp_line
			(start -3.64998 -3.350006)
			(end 3.64998 -3.350006)
			(stroke
				(width 0.1)
				(type default)
			)
			(layer "F.Fab")
		)
		(fp_line
			(start 3.64998 3.350006)
			(end -3.64998 3.350006)
			(stroke
				(width 0.1)
				(type default)
			)
			(layer "F.Fab")
		)
		(fp_line
			(start -3.64998 3.350006)
			(end -3.64998 -3.350006)
			(stroke
				(width 0.1)
				(type default)
			)
			(layer "F.Fab")
		)
		(pad "1" smd rect
			(at -2.92481 0 90)
			(size 2.15392 3.302)
			(layers "F.Cu" "F.Mask" "F.Paste")
			(net "SW_PVPP_HBM_CPU1_SW")
		)
		(pad "2" smd rect
			(at 2.92481 0 90)
			(size 2.15392 3.302)
			(layers "F.Cu" "F.Mask" "F.Paste")
			(net "PVPP_HBM_CPU1")
		)
	)
	(footprint ""
		(layer "F.Cu")
		(at 371.39753 -402.371052 -90)
		(property "Reference" "C934"
			(at 0 0 270)
			(layer "F.SilkS")
			(hide yes)
			(effects
				(font
					(size 1.27 1.27)
				)
			)
		)
		(property "Value" ""
			(at 0 0 270)
			(layer "F.Fab")
			(effects
				(font
					(size 1.27 1.27)
				)
			)
		)
		(duplicate_pad_numbers_are_jumpers no)
		(fp_line
			(start -0.299974 0.150114)
			(end -0.299974 -0.150114)
			(stroke
				(width 0.1)
				(type default)
			)
			(layer "F.Fab")
		)
		(fp_line
			(start 0.299974 0.150114)
			(end -0.299974 0.150114)
			(stroke
				(width 0.1)
				(type default)
			)
			(layer "F.Fab")
		)
		(fp_line
			(start -0.299974 -0.150114)
			(end 0.299974 -0.150114)
			(stroke
				(width 0.1)
				(type default)
			)
			(layer "F.Fab")
		)
		(fp_line
			(start 0.299974 -0.150114)
			(end 0.299974 0.150114)
			(stroke
				(width 0.1)
				(type default)
			)
			(layer "F.Fab")
		)
		(pad "1" smd rect
			(at -0.2667 0 270)
			(size 0.3048 0.381)
			(layers "F.Cu" "F.Mask" "F.Paste")
			(net "P5E_CPU0_PE2_TX_C_DN<15>")
		)
		(pad "2" smd rect
			(at 0.2667 0 270)
			(size 0.3048 0.381)
			(layers "F.Cu" "F.Mask" "F.Paste")
			(net "P5E_CPU0_PE2_TX_DN<15>")
		)
	)
)
